(kicad_pcb
	(version 20260206)
	(generator "pcbnew")
	(generator_version "10.0")
	(general
		(thickness 1.6)
		(legacy_teardrops no)
	)
	(paper "A4")
	(title_block
		(title "04192023_DAF0TMB3IC0_F0TG_MB_C_brd_V02_OCP.brd")
		(comment 1 "Grand Teton / footprints 7596-7602 of 8354")
	)
	(layers
		(0 "F.Cu" signal "TOP")
		(4 "In1.Cu" signal "GND")
		(6 "In2.Cu" signal "IN1")
		(8 "In3.Cu" signal "GND1")
		(10 "In4.Cu" signal "IN2")
		(12 "In5.Cu" signal "GND2")
		(14 "In6.Cu" signal "IN3")
		(16 "In7.Cu" signal "GND3")
		(18 "In8.Cu" signal "VCC")
		(20 "In9.Cu" signal "VCC1")
		(22 "In10.Cu" signal "GND4")
		(24 "In11.Cu" signal "IN4")
		(26 "In12.Cu" signal "GND5")
		(28 "In13.Cu" signal "IN5")
		(30 "In14.Cu" signal "GND6")
		(32 "In15.Cu" signal "IN6")
		(34 "In16.Cu" signal "GND7")
		(2 "B.Cu" signal "BOTTOM")
		(9 "F.Adhes" user "F.Adhesive")
		(11 "B.Adhes" user "B.Adhesive")
		(13 "F.Paste" user "Package Geometry/Pastemask Top")
		(15 "B.Paste" user "Package Geometry/Pastemask Bottom")
		(5 "F.SilkS" user "Ref Des/Silkscreen Top")
		(7 "B.SilkS" user "Ref Des/Silkscreen Bottom")
		(1 "F.Mask" user "Board Geometry/Soldermask Top")
		(3 "B.Mask" user "Board Geometry/Soldermask Bottom")
		(17 "Dwgs.User" user "User.Drawings")
		(19 "Cmts.User" user "User.Comments")
		(21 "Eco1.User" user "User.Eco1")
		(23 "Eco2.User" user "User.Eco2")
		(25 "Edge.Cuts" user "Board Geometry/Outline")
		(27 "Margin" user)
		(31 "F.CrtYd" user "Package Geometry/Place Bound Top")
		(29 "B.CrtYd" user "Package Geometry/Place Bound Bottom")
		(35 "F.Fab" user "Ref Des/Assembly Top")
		(33 "B.Fab" user "Ref Des/Assembly Bottom")
	)
	(footprint ""
		(layer "B.Cu")
		(at 8.382 -81.153 90)
		(property "Reference" "R8014"
			(at 0 0 90)
			(layer "B.SilkS")
			(hide yes)
			(effects
				(font
					(size 1.27 1.27)
				)
				(justify mirror)
			)
		)
		(property "Value" ""
			(at 0 0 90)
			(layer "B.Fab")
			(effects
				(font
					(size 1.27 1.27)
				)
				(justify mirror)
			)
		)
		(duplicate_pad_numbers_are_jumpers no)
		(fp_line
			(start 0.7874 -0.4064)
			(end -0.7874 -0.4064)
			(stroke
				(width 0.1524)
				(type default)
			)
			(layer "B.SilkS")
		)
		(fp_line
			(start -0.7874 -0.4064)
			(end -0.7874 0.4064)
			(stroke
				(width 0.1524)
				(type default)
			)
			(layer "B.SilkS")
		)
		(fp_line
			(start 0.7874 0.4064)
			(end 0.7874 -0.4064)
			(stroke
				(width 0.1524)
				(type default)
			)
			(layer "B.SilkS")
		)
		(fp_line
			(start -0.7874 0.4064)
			(end 0.7874 0.4064)
			(stroke
				(width 0.1524)
				(type default)
			)
			(layer "B.SilkS")
		)
		(fp_line
			(start 0.67945 -0.305054)
			(end 0.12065 -0.305054)
			(stroke
				(width 0.1)
				(type default)
			)
			(layer "B.Fab")
		)
		(fp_line
			(start 0.12065 -0.305054)
			(end 0.12065 -0.2794)
			(stroke
				(width 0.1)
				(type default)
			)
			(layer "B.Fab")
		)
		(fp_line
			(start -0.12065 -0.3048)
			(end -0.67945 -0.3048)
			(stroke
				(width 0.1)
				(type default)
			)
			(layer "B.Fab")
		)
		(fp_line
			(start -0.67945 -0.3048)
			(end -0.67945 0.3048)
			(stroke
				(width 0.1)
				(type default)
			)
			(layer "B.Fab")
		)
		(fp_line
			(start 0.12065 -0.2794)
			(end -0.12065 -0.2794)
			(stroke
				(width 0.1)
				(type default)
			)
			(layer "B.Fab")
		)
		(fp_line
			(start -0.12065 -0.2794)
			(end -0.12065 -0.3048)
			(stroke
				(width 0.1)
				(type default)
			)
			(layer "B.Fab")
		)
		(fp_line
			(start 0.12065 0.2794)
			(end 0.12065 0.3048)
			(stroke
				(width 0.1)
				(type default)
			)
			(layer "B.Fab")
		)
		(fp_line
			(start -0.120396 0.2794)
			(end 0.12065 0.2794)
			(stroke
				(width 0.1)
				(type default)
			)
			(layer "B.Fab")
		)
		(fp_line
			(start 0.67945 0.3048)
			(end 0.67945 -0.305054)
			(stroke
				(width 0.1)
				(type default)
			)
			(layer "B.Fab")
		)
		(fp_line
			(start 0.12065 0.3048)
			(end 0.67945 0.3048)
			(stroke
				(width 0.1)
				(type default)
			)
			(layer "B.Fab")
		)
		(fp_line
			(start -0.120396 0.3048)
			(end -0.120396 0.2794)
			(stroke
				(width 0.1)
				(type default)
			)
			(layer "B.Fab")
		)
		(fp_line
			(start -0.67945 0.3048)
			(end -0.120396 0.3048)
			(stroke
				(width 0.1)
				(type default)
			)
			(layer "B.Fab")
		)
		(pad "1" smd circle
			(at 0.40005 0 270)
			(size 0 0)
			(layers "B.Cu" "B.Mask" "B.Paste")
			(net "OCP_SFF_PRSNT23_R_N")
		)
		(pad "2" smd circle
			(at -0.40005 0 270)
			(size 0 0)
			(layers "B.Cu" "B.Mask" "B.Paste")
			(net "OCP_SFF_PRSNT23_R1_N")
		)
	)
	(footprint ""
		(layer "B.Cu")
		(at 60.578492 -386.766562 90)
		(property "Reference" "C187"
			(at 0 0 90)
			(layer "B.SilkS")
			(hide yes)
			(effects
				(font
					(size 1.27 1.27)
				)
				(justify mirror)
			)
		)
		(property "Value" ""
			(at 0 0 90)
			(layer "B.Fab")
			(effects
				(font
					(size 1.27 1.27)
				)
				(justify mirror)
			)
		)
		(duplicate_pad_numbers_are_jumpers no)
		(fp_line
			(start 0.299974 -0.150114)
			(end -0.299974 -0.150114)
			(stroke
				(width 0.1)
				(type default)
			)
			(layer "B.Fab")
		)
		(fp_line
			(start -0.299974 -0.150114)
			(end -0.299974 0.150114)
			(stroke
				(width 0.1)
				(type default)
			)
			(layer "B.Fab")
		)
		(fp_line
			(start 0.299974 0.150114)
			(end 0.299974 -0.150114)
			(stroke
				(width 0.1)
				(type default)
			)
			(layer "B.Fab")
		)
		(fp_line
			(start -0.299974 0.150114)
			(end 0.299974 0.150114)
			(stroke
				(width 0.1)
				(type default)
			)
			(layer "B.Fab")
		)
		(pad "1" smd rect
			(at 0.2667 0 270)
			(size 0.3048 0.381)
			(layers "B.Cu" "B.Mask" "B.Paste")
			(net "P0V9_CPU1_RT0_2A_2D")
		)
		(pad "2" smd rect
			(at -0.2667 0 270)
			(size 0.3048 0.381)
			(layers "B.Cu" "B.Mask" "B.Paste")
			(net "GND")
		)
	)
	(footprint ""
		(layer "B.Cu")
		(at 350.429576 -171.35094 90)
		(property "Reference" "PC502_1"
			(at 0 0 90)
			(layer "B.SilkS")
			(hide yes)
			(effects
				(font
					(size 1.27 1.27)
				)
				(justify mirror)
			)
		)
		(property "Value" ""
			(at 0 0 90)
			(layer "B.Fab")
			(effects
				(font
					(size 1.27 1.27)
				)
				(justify mirror)
			)
		)
		(duplicate_pad_numbers_are_jumpers no)
		(fp_line
			(start 1.524 -0.762)
			(end -1.524 -0.762)
			(stroke
				(width 0.1524)
				(type default)
			)
			(layer "B.SilkS")
		)
		(fp_line
			(start -1.524 -0.762)
			(end -1.524 0.762)
			(stroke
				(width 0.1524)
				(type default)
			)
			(layer "B.SilkS")
		)
		(fp_line
			(start 1.524 0.762)
			(end 1.524 -0.762)
			(stroke
				(width 0.1524)
				(type default)
			)
			(layer "B.SilkS")
		)
		(fp_line
			(start -1.524 0.762)
			(end 1.524 0.762)
			(stroke
				(width 0.1524)
				(type default)
			)
			(layer "B.SilkS")
		)
		(fp_line
			(start 1.1049 -0.724916)
			(end 1.1049 0.724916)
			(stroke
				(width 0.1)
				(type default)
			)
			(layer "B.Fab")
		)
		(fp_line
			(start -1.1049 -0.724916)
			(end 1.1049 -0.724916)
			(stroke
				(width 0.1)
				(type default)
			)
			(layer "B.Fab")
		)
		(fp_line
			(start 1.1049 0.724916)
			(end -1.1049 0.724916)
			(stroke
				(width 0.1)
				(type default)
			)
			(layer "B.Fab")
		)
		(fp_line
			(start -1.1049 0.724916)
			(end -1.1049 -0.724916)
			(stroke
				(width 0.1)
				(type default)
			)
			(layer "B.Fab")
		)
		(pad "1" smd rect
			(at 0.889 0 90)
			(size 1.016 1.27)
			(layers "B.Cu" "B.Mask" "B.Paste")
			(net "PVDDCR_CPU0_P0")
		)
		(pad "2" smd rect
			(at -0.889 0 90)
			(size 1.016 1.27)
			(layers "B.Cu" "B.Mask" "B.Paste")
			(net "GND")
		)
	)
	(footprint ""
		(layer "B.Cu")
		(at 459.053184 -65.794382 90)
		(property "Reference" "PC1869"
			(at 0 0 90)
			(layer "B.SilkS")
			(hide yes)
			(effects
				(font
					(size 1.27 1.27)
				)
				(justify mirror)
			)
		)
		(property "Value" ""
			(at 0 0 90)
			(layer "B.Fab")
			(effects
				(font
					(size 1.27 1.27)
				)
				(justify mirror)
			)
		)
		(duplicate_pad_numbers_are_jumpers no)
		(fp_line
			(start 0.7874 -0.4064)
			(end -0.7874 -0.4064)
			(stroke
				(width 0.1524)
				(type default)
			)
			(layer "B.SilkS")
		)
		(fp_line
			(start -0.7874 -0.4064)
			(end -0.7874 0.4064)
			(stroke
				(width 0.1524)
				(type default)
			)
			(layer "B.SilkS")
		)
		(fp_line
			(start 0.7874 0.4064)
			(end 0.7874 -0.4064)
			(stroke
				(width 0.1524)
				(type default)
			)
			(layer "B.SilkS")
		)
		(fp_line
			(start -0.7874 0.4064)
			(end 0.7874 0.4064)
			(stroke
				(width 0.1524)
				(type default)
			)
			(layer "B.SilkS")
		)
		(fp_line
			(start 0.67945 -0.305054)
			(end 0.12065 -0.305054)
			(stroke
				(width 0.1)
				(type default)
			)
			(layer "B.Fab")
		)
		(fp_line
			(start 0.12065 -0.305054)
			(end 0.12065 -0.2794)
			(stroke
				(width 0.1)
				(type default)
			)
			(layer "B.Fab")
		)
		(fp_line
			(start -0.12065 -0.3048)
			(end -0.67945 -0.3048)
			(stroke
				(width 0.1)
				(type default)
			)
			(layer "B.Fab")
		)
		(fp_line
			(start -0.67945 -0.3048)
			(end -0.67945 0.3048)
			(stroke
				(width 0.1)
				(type default)
			)
			(layer "B.Fab")
		)
		(fp_line
			(start 0.12065 -0.2794)
			(end -0.12065 -0.2794)
			(stroke
				(width 0.1)
				(type default)
			)
			(layer "B.Fab")
		)
		(fp_line
			(start -0.12065 -0.2794)
			(end -0.12065 -0.3048)
			(stroke
				(width 0.1)
				(type default)
			)
			(layer "B.Fab")
		)
		(fp_line
			(start 0.12065 0.2794)
			(end 0.12065 0.3048)
			(stroke
				(width 0.1)
				(type default)
			)
			(layer "B.Fab")
		)
		(fp_line
			(start -0.120396 0.2794)
			(end 0.12065 0.2794)
			(stroke
				(width 0.1)
				(type default)
			)
			(layer "B.Fab")
		)
		(fp_line
			(start 0.67945 0.3048)
			(end 0.67945 -0.305054)
			(stroke
				(width 0.1)
				(type default)
			)
			(layer "B.Fab")
		)
		(fp_line
			(start 0.12065 0.3048)
			(end 0.67945 0.3048)
			(stroke
				(width 0.1)
				(type default)
			)
			(layer "B.Fab")
		)
		(fp_line
			(start -0.120396 0.3048)
			(end -0.120396 0.2794)
			(stroke
				(width 0.1)
				(type default)
			)
			(layer "B.Fab")
		)
		(fp_line
			(start -0.67945 0.3048)
			(end -0.120396 0.3048)
			(stroke
				(width 0.1)
				(type default)
			)
			(layer "B.Fab")
		)
		(pad "1" smd circle
			(at 0.40005 0 270)
			(size 0 0)
			(layers "B.Cu" "B.Mask" "B.Paste")
			(net "P3V3_AUX")
		)
		(pad "2" smd circle
			(at -0.40005 0 270)
			(size 0 0)
			(layers "B.Cu" "B.Mask" "B.Paste")
			(net "GND")
		)
	)
	(footprint ""
		(layer "B.Cu")
		(at 127.536448 -156.393134 -90)
		(property "Reference" "PC353_3"
			(at 0 0 90)
			(layer "B.SilkS")
			(hide yes)
			(effects
				(font
					(size 1.27 1.27)
				)
				(justify mirror)
			)
		)
		(property "Value" ""
			(at 0 0 90)
			(layer "B.Fab")
			(effects
				(font
					(size 1.27 1.27)
				)
				(justify mirror)
			)
		)
		(duplicate_pad_numbers_are_jumpers no)
		(fp_line
			(start -1.524 0.762)
			(end 1.524 0.762)
			(stroke
				(width 0.1524)
				(type default)
			)
			(layer "B.SilkS")
		)
		(fp_line
			(start 1.524 0.762)
			(end 1.524 -0.762)
			(stroke
				(width 0.1524)
				(type default)
			)
			(layer "B.SilkS")
		)
		(fp_line
			(start -1.524 -0.762)
			(end -1.524 0.762)
			(stroke
				(width 0.1524)
				(type default)
			)
			(layer "B.SilkS")
		)
		(fp_line
			(start 1.524 -0.762)
			(end -1.524 -0.762)
			(stroke
				(width 0.1524)
				(type default)
			)
			(layer "B.SilkS")
		)
		(fp_line
			(start -1.1049 0.724916)
			(end -1.1049 -0.724916)
			(stroke
				(width 0.1)
				(type default)
			)
			(layer "B.Fab")
		)
		(fp_line
			(start 1.1049 0.724916)
			(end -1.1049 0.724916)
			(stroke
				(width 0.1)
				(type default)
			)
			(layer "B.Fab")
		)
		(fp_line
			(start -1.1049 -0.724916)
			(end 1.1049 -0.724916)
			(stroke
				(width 0.1)
				(type default)
			)
			(layer "B.Fab")
		)
		(fp_line
			(start 1.1049 -0.724916)
			(end 1.1049 0.724916)
			(stroke
				(width 0.1)
				(type default)
			)
			(layer "B.Fab")
		)
		(pad "1" smd rect
			(at 0.889 0 270)
			(size 1.016 1.27)
			(layers "B.Cu" "B.Mask" "B.Paste")
			(net "SW_P12V_AUX_PVDDCR_SOC_P1_FLT")
		)
		(pad "2" smd rect
			(at -0.889 0 270)
			(size 1.016 1.27)
			(layers "B.Cu" "B.Mask" "B.Paste")
			(net "GND")
		)
	)
	(footprint ""
		(layer "B.Cu")
		(at 325.799958 -203.917296 90)
		(property "Reference" "R156"
			(at 0 0 90)
			(layer "B.SilkS")
			(hide yes)
			(effects
				(font
					(size 1.27 1.27)
				)
				(justify mirror)
			)
		)
		(property "Value" ""
			(at 0 0 90)
			(layer "B.Fab")
			(effects
				(font
					(size 1.27 1.27)
				)
				(justify mirror)
			)
		)
		(duplicate_pad_numbers_are_jumpers no)
		(fp_line
			(start 0.7874 -0.4064)
			(end -0.7874 -0.4064)
			(stroke
				(width 0.1524)
				(type default)
			)
			(layer "B.SilkS")
		)
		(fp_line
			(start -0.7874 -0.4064)
			(end -0.7874 0.4064)
			(stroke
				(width 0.1524)
				(type default)
			)
			(layer "B.SilkS")
		)
		(fp_line
			(start 0.7874 0.4064)
			(end 0.7874 -0.4064)
			(stroke
				(width 0.1524)
				(type default)
			)
			(layer "B.SilkS")
		)
		(fp_line
			(start -0.7874 0.4064)
			(end 0.7874 0.4064)
			(stroke
				(width 0.1524)
				(type default)
			)
			(layer "B.SilkS")
		)
		(fp_line
			(start 0.67945 -0.305054)
			(end 0.12065 -0.305054)
			(stroke
				(width 0.1)
				(type default)
			)
			(layer "B.Fab")
		)
		(fp_line
			(start 0.12065 -0.305054)
			(end 0.12065 -0.2794)
			(stroke
				(width 0.1)
				(type default)
			)
			(layer "B.Fab")
		)
		(fp_line
			(start -0.12065 -0.3048)
			(end -0.67945 -0.3048)
			(stroke
				(width 0.1)
				(type default)
			)
			(layer "B.Fab")
		)
		(fp_line
			(start -0.67945 -0.3048)
			(end -0.67945 0.3048)
			(stroke
				(width 0.1)
				(type default)
			)
			(layer "B.Fab")
		)
		(fp_line
			(start 0.12065 -0.2794)
			(end -0.12065 -0.2794)
			(stroke
				(width 0.1)
				(type default)
			)
			(layer "B.Fab")
		)
		(fp_line
			(start -0.12065 -0.2794)
			(end -0.12065 -0.3048)
			(stroke
				(width 0.1)
				(type default)
			)
			(layer "B.Fab")
		)
		(fp_line
			(start 0.12065 0.2794)
			(end 0.12065 0.3048)
			(stroke
				(width 0.1)
				(type default)
			)
			(layer "B.Fab")
		)
		(fp_line
			(start -0.120396 0.2794)
			(end 0.12065 0.2794)
			(stroke
				(width 0.1)
				(type default)
			)
			(layer "B.Fab")
		)
		(fp_line
			(start 0.67945 0.3048)
			(end 0.67945 -0.305054)
			(stroke
				(width 0.1)
				(type default)
			)
			(layer "B.Fab")
		)
		(fp_line
			(start 0.12065 0.3048)
			(end 0.67945 0.3048)
			(stroke
				(width 0.1)
				(type default)
			)
			(layer "B.Fab")
		)
		(fp_line
			(start -0.120396 0.3048)
			(end -0.120396 0.2794)
			(stroke
				(width 0.1)
				(type default)
			)
			(layer "B.Fab")
		)
		(fp_line
			(start -0.67945 0.3048)
			(end -0.120396 0.3048)
			(stroke
				(width 0.1)
				(type default)
			)
			(layer "B.Fab")
		)
		(pad "1" smd circle
			(at 0.40005 0 270)
			(size 0 0)
			(layers "B.Cu" "B.Mask" "B.Paste")
			(net "CPU0_XTRIG_R2_L4")
		)
		(pad "2" smd circle
			(at -0.40005 0 270)
			(size 0 0)
			(layers "B.Cu" "B.Mask" "B.Paste")
			(net "CPU0_XTRIG_L4")
		)
	)
	(footprint ""
		(layer "B.Cu")
		(at 236.67593 -49.120044)
		(property "Reference" "C1282"
			(at 0 0 0)
			(layer "B.SilkS")
			(hide yes)
			(effects
				(font
					(size 1.27 1.27)
				)
				(justify mirror)
			)
		)
		(property "Value" ""
			(at 0 0 0)
			(layer "B.Fab")
			(effects
				(font
					(size 1.27 1.27)
				)
				(justify mirror)
			)
		)
		(duplicate_pad_numbers_are_jumpers no)
		(fp_line
			(start -0.7874 -0.4064)
			(end -0.7874 0.4064)
			(stroke
				(width 0.1524)
				(type default)
			)
			(layer "B.SilkS")
		)
		(fp_line
			(start -0.7874 0.4064)
			(end 0.7874 0.4064)
			(stroke
				(width 0.1524)
				(type default)
			)
			(layer "B.SilkS")
		)
		(fp_line
			(start 0.7874 -0.4064)
			(end -0.7874 -0.4064)
			(stroke
				(width 0.1524)
				(type default)
			)
			(layer "B.SilkS")
		)
		(fp_line
			(start 0.7874 0.4064)
			(end 0.7874 -0.4064)
			(stroke
				(width 0.1524)
				(type default)
			)
			(layer "B.SilkS")
		)
		(fp_line
			(start -0.67945 -0.3048)
			(end -0.67945 0.3048)
			(stroke
				(width 0.1)
				(type default)
			)
			(layer "B.Fab")
		)
		(fp_line
			(start -0.67945 0.3048)
			(end -0.120396 0.3048)
			(stroke
				(width 0.1)
				(type default)
			)
			(layer "B.Fab")
		)
		(fp_line
			(start -0.12065 -0.3048)
			(end -0.67945 -0.3048)
			(stroke
				(width 0.1)
				(type default)
			)
			(layer "B.Fab")
		)
		(fp_line
			(start -0.12065 -0.2794)
			(end -0.12065 -0.3048)
			(stroke
				(width 0.1)
				(type default)
			)
			(layer "B.Fab")
		)
		(fp_line
			(start -0.120396 0.2794)
			(end 0.12065 0.2794)
			(stroke
				(width 0.1)
				(type default)
			)
			(layer "B.Fab")
		)
		(fp_line
			(start -0.120396 0.3048)
			(end -0.120396 0.2794)
			(stroke
				(width 0.1)
				(type default)
			)
			(layer "B.Fab")
		)
		(fp_line
			(start 0.12065 -0.305054)
			(end 0.12065 -0.2794)
			(stroke
				(width 0.1)
				(type default)
			)
			(layer "B.Fab")
		)
		(fp_line
			(start 0.12065 -0.2794)
			(end -0.12065 -0.2794)
			(stroke
				(width 0.1)
				(type default)
			)
			(layer "B.Fab")
		)
		(fp_line
			(start 0.12065 0.2794)
			(end 0.12065 0.3048)
			(stroke
				(width 0.1)
				(type default)
			)
			(layer "B.Fab")
		)
		(fp_line
			(start 0.12065 0.3048)
			(end 0.67945 0.3048)
			(stroke
				(width 0.1)
				(type default)
			)
			(layer "B.Fab")
		)
		(fp_line
			(start 0.67945 -0.305054)
			(end 0.12065 -0.305054)
			(stroke
				(width 0.1)
				(type default)
			)
			(layer "B.Fab")
		)
		(fp_line
			(start 0.67945 0.3048)
			(end 0.67945 -0.305054)
			(stroke
				(width 0.1)
				(type default)
			)
			(layer "B.Fab")
		)
		(pad "1" smd circle
			(at 0.40005 0 180)
			(size 0 0)
			(layers "B.Cu" "B.Mask" "B.Paste")
			(net "P3V3_E1S_0")
		)
		(pad "2" smd circle
			(at -0.40005 0 180)
			(size 0 0)
			(layers "B.Cu" "B.Mask" "B.Paste")
			(net "GND")
		)
	)
)
